FILE_TYPE = CONNECTIVITY;
{Allegro Design Entry HDL 16.6-p007 (v16-6-112F) 10/10/2012}
"PAGE_NUMBER" = 227;
0"NC";
1"PVDDQ_KLM\g";
2"GND\g";
3"GND\g";
4"P5V_STBY\g";
5"GND\g";
6"GND\g";
7"GND\g";
8"GND\g";
9"GND\g";
10"GND\g";
11"GND\g";
12"GND\g";
13"PVDDQ_KLM\g";
14"GND\g";
15"GND\g";
16"GND\g";
17"VR_FET_SW_P12V_STBY_PVDDQ_KLM\g";
18"GND\g";
19"VR_FET_SW_P12V_STBY_PVDDQ_KLM\g";
20"P5V_STBY\g";
21"VR_PVDDQ_KLM_PH2_VCIN";
22"VR_PVDDQ_KLM_PWM2";
23"VR_PVDDQ_KLM_PH1_PHASE";
24"VR_PVDDQ_KLM_PWM1";
25"VR_PVDDQ_KLM_PH1_VCIN";
26"VR_PVDDQ_KLM_AIREF2";
27"TP_PVDDQ_KLM_PH2_GL_0";
28"TP_PVDDQ_KLM_PH2_GL_1";
29"VR_PVDDQ_KLM_PH2_BOOT_R";
30"VR_PVDDQ_KLM_PH2_PHASE";
31"VR_PVDDQ_KLM_PH2_SW";
32"ISENSE_PVDDQ_KLM_PH2_IMON";
33"VR_PVDDQ_KLM_PH2_OCSET"VOLTAGE"3.6";
34"VR_PVDDQ_KLM_PH2_RC";
35"A_TSENSE_PVDDQ_KLM";
36"VR_PVDDQ_KLM_PH2_BOOT";
37"VR_PVDDQ_KLM_PH1_OCSET"VOLTAGE"3.6";
38"VR_PVDDQ_KLM_PH1_RC";
39"VR_PVDDQ_KLM_PH1_BOOT";
40"TP_PVDDQ_KLM_PH1_GL_0";
41"TP_PVDDQ_KLM_PH1_GL_1";
42"ISENSE_PVDDQ_KLM_PH1_IMON";
43"VR_PVDDQ_KLM_PH1_BOOT_R";
44"VR_PVDDQ_KLM_AIREF1";
45"VR_PVDDQ_KLM_PH1_SW";
46"A_TSENSE_PVDDQ_KLM";
%"PVDDQ_KLM"
"1","(4350,2025)","0","mstr_symbols","I1";
;
HDL_POWER"PVDDQ_KLM"
BODY_TYPE"PLUMBING"
VOLTAGE"1.2V"
CDS_LIB"mstr_symbols";
"G\NAC"1;
%"IR354XX"
"1","(1825,2225)","0","mstr_discrete","I101";
;
CDS_SEC"1"
LOCATION"EU1A2"
NO_XNET_CONNECTION"1"
MATERIAL"IC"
PART_NUMBER"H73688-001"
VALUE"IR35411"
CDS_LIB"mstr_discrete"
PACK_TYPE"SM"
SEC_TYPE"SM"
SEC"1"
CDS_LOCATION"EU1A2";
"TOUT_FLT"
$PN"36"46;
"NC"
$PN"31"0;
"OCSET"
$PN"37"37;
"IOUT"
$PN"38"42;
"SW"
$PN"10"45;
"BOOST"
$PN"33"43;
"REFIN"
$PN"39"44;
"PWM"
$PN"34"24;
"PHASE"
$PN"32"23;
"VIN<0>"
$PN"25"19;
"VCC"
$PN"3"25;
"VIN<1>"
$PN"30"19;
"EN"
$PN"35"4;
"VDRV"
$PN"4"4;
"VOS"
$PN"1"1;
"LGND"
$PN"2"11;
"PGND<1>"
$PN"7"11;
"PGND<2>"
$PN"40"11;
"PGND<0>"
$PN"5"11;
"GL<0>"
$PN"6"40;
"GL<1>"
$PN"41"41;
%"IR354XX"
"1","(1825,-25)","0","mstr_discrete","I102";
;
CDS_SEC"1"
BOM_SS"NOPOP"
PART_NUMBER"H73688-001"
MATERIAL"IC"
LOCATION"EU1A1"
NO_XNET_CONNECTION"1"
CDS_LIB"mstr_discrete"
CDS_LOCATION"EU1A1"
SEC"1"
SEC_TYPE"SM"
PACK_TYPE"SM"
VALUE"IR35411";
"TOUT_FLT"
$PN"36"35;
"NC"
$PN"31"0;
"OCSET"
$PN"37"33;
"IOUT"
$PN"38"32;
"SW"
$PN"10"31;
"BOOST"
$PN"33"29;
"REFIN"
$PN"39"26;
"PWM"
$PN"34"22;
"PHASE"
$PN"32"30;
"VIN<0>"
$PN"25"17;
"VCC"
$PN"3"21;
"VIN<1>"
$PN"30"17;
"EN"
$PN"35"20;
"VDRV"
$PN"4"20;
"VOS"
$PN"1"13;
"LGND"
$PN"2"16;
"PGND<1>"
$PN"7"16;
"PGND<2>"
$PN"40"16;
"PGND<0>"
$PN"5"16;
"GL<0>"
$PN"6"27;
"GL<1>"
$PN"41"28;
%"RES"
"2","(4650,2400)","0","mstr_discrete","I103";
;
CDS_SEC"1"
CDS_LOCATION"R1A3"
MATERIAL"EMPTY"
PART_NUMBER"G21796-187"
PACK_TYPE"0402"
TOLERANCE"1%"
LOCATION"R1A3"
VALUE"68.1K"
WATTAGE"1/16W"
CDS_LIB"mstr_discrete"
SEC"1"
SEC_TYPE"0402";
"A"
$PN"1"37;
"B"
$PN"2"2;
%"GND"
"1","(4650,2200)","0","mstr_symbols","I104";
;
HDL_POWER"GND"
BODY_TYPE"PLUMBING"
VOLTAGE"0"
CDS_LIB"mstr_symbols"
SIZE"1B"
BOM_COST"PROC_VRD_VCCIN_CPU0"
ROOM"PVCCIN_CPU0_PWR_VR";
"A\NAC"2;
%"RES"
"2","(4650,150)","0","mstr_discrete","I105";
;
CDS_SEC"1"
CDS_LOCATION"R1A2"
PACK_TYPE"0402"
VALUE"68.1K"
TOLERANCE"1%"
MATERIAL"EMPTY"
WATTAGE"1/16W"
LOCATION"R1A2"
BOM_SS"NOPOP"
PART_NUMBER"G21796-187"
CDS_LIB"mstr_discrete"
SEC"1"
SEC_TYPE"0402";
"A"
$PN"1"33;
"B"
$PN"2"3;
%"GND"
"1","(4650,-25)","0","mstr_symbols","I106";
;
ROOM"PVCCIN_CPU0_PWR_VR"
BOM_COST"PROC_VRD_VCCIN_CPU0"
CDS_LIB"mstr_symbols"
VOLTAGE"0"
SIZE"1B"
BODY_TYPE"PLUMBING"
HDL_POWER"GND";
"A\NAC"3;
%"P5V_STBY"
"1","(600,3200)","0","mstr_symbols","I107";
;
HDL_POWER"P5V_STBY"
BODY_TYPE"PLUMBING"
VOLTAGE"5.0V"
CDS_LIB"mstr_symbols"
SIZE"1B";
"G\NAC"4;
%"CAP_A"
"1","(1150,1725)","0","dev_discrete","I109";
;
CDS_SEC"1"
CDS_LOCATION"CT7"
PART_NUMBER"A36096-030"
TOLERANCE"10%"
PACK_TYPE"0402V"
VOLTAGE"16V"
LOCATION"CT7"
VALUE"0.1UF"
MATERIAL"X7R"
POP"NOPOP"
ROOM"PVCCIN_CPU0_PWR_VR"
CDS_LIB"dev_discrete"
SEC"1"
SEC_TYPE"0402V";
"B"
$PN"2"5;
"A"
$PN"1"44;
%"GND"
"1","(1150,1475)","0","mstr_symbols","I110";
;
HDL_POWER"GND"
BODY_TYPE"PLUMBING"
ROOM"PVCCIN_CPU0_PWR_VR"
BOM_COST"PROC_VRD_VCCIN_CPU0"
SIZE"1B"
VOLTAGE"0"
CDS_LIB"mstr_symbols";
"A\NAC"5;
%"GND"
"1","(2825,1125)","0","mstr_symbols","I113";
;
HDL_POWER"GND"
BODY_TYPE"PLUMBING"
CDS_LIB"mstr_symbols"
SIZE"1B"
VOLTAGE"0"
BOM_COST"PROC_VRD_VCCIN_CPU0"
ROOM"PVCCIN_CPU0_PWR_VR";
"A\NAC"6;
%"CAP"
"1","(3050,2200)","0","mstr_discrete","I114";
;
CDS_SEC"1"
CDS_LOCATION"CT8"
POP"NOPOP"
VALUE"1000PF"
LOCATION"CT8"
VOLTAGE"50V"
TOLERANCE"10%"
MATERIAL"X7R"
PART_NUMBER"A36096-046"
PACK_TYPE"0402LF"
CDS_LIB"mstr_discrete"
ROOM"VDDQ_KLM_PWR_VR"
SEC"1"
SEC_TYPE"0402LF";
"A"
$PN"1"46;
"B"
$PN"2"7;
%"GND"
"1","(3050,2000)","0","mstr_symbols","I115";
;
HDL_POWER"GND"
BODY_TYPE"PLUMBING"
CDS_LIB"mstr_symbols"
ROOM"VDDQ_KLM_PWR_VR"
VOLTAGE"0"
SIZE"1B";
"A\NAC"7;
%"GND"
"1","(2925,-1000)","0","mstr_symbols","I117";
;
CDS_LIB"mstr_symbols"
SIZE"1B"
VOLTAGE"0"
BOM_COST"PROC_VRD_VCCIN_CPU0"
ROOM"PVCCIN_CPU0_PWR_VR"
BODY_TYPE"PLUMBING"
HDL_POWER"GND";
"A\NAC"8;
%"CAP"
"1","(2950,25)","0","mstr_discrete","I119";
;
CDS_SEC"1"
CDS_LOCATION"CT10"
BOM_SS"NOPOP"
PACK_TYPE"0402LF"
VALUE"1000PF"
VOLTAGE"50V"
TOLERANCE"10%"
MATERIAL"X7R"
LOCATION"CT10"
PART_NUMBER"A36096-046"
POP"NOPOP"
SEC_TYPE"0402LF"
SEC"1"
CDS_LIB"mstr_discrete"
ROOM"VDDQ_KLM_PWR_VR";
"A"
$PN"1"35;
"B"
$PN"2"9;
%"GND"
"1","(2950,-175)","0","mstr_symbols","I120";
;
CDS_LIB"mstr_symbols"
ROOM"VDDQ_KLM_PWR_VR"
VOLTAGE"0"
SIZE"1B"
BODY_TYPE"PLUMBING"
HDL_POWER"GND";
"A\NAC"9;
%"CAP_A"
"1","(1150,-800)","0","dev_discrete","I122";
;
CDS_SEC"1"
CDS_LOCATION"CT12"
BOM_SS"NOPOP"
POP"NOPOP"
PACK_TYPE"0402V"
PART_NUMBER"A36096-030"
MATERIAL"X7R"
VALUE"0.1UF"
VOLTAGE"16V"
TOLERANCE"10%"
LOCATION"CT12"
SEC"1"
SEC_TYPE"0402V"
ROOM"PVCCIN_CPU0_PWR_VR"
CDS_LIB"dev_discrete";
"B"
$PN"2"10;
"A"
$PN"1"26;
%"GND"
"1","(1150,-1000)","0","mstr_symbols","I123";
;
ROOM"PVCCIN_CPU0_PWR_VR"
BOM_COST"PROC_VRD_VCCIN_CPU0"
SIZE"1B"
VOLTAGE"0"
CDS_LIB"mstr_symbols"
BODY_TYPE"PLUMBING"
HDL_POWER"GND";
"A\NAC"10;
%"CAP"
"1","(2825,1750)","0","mstr_discrete","I134";
;
CDS_SEC"1"
CDS_LOCATION"CT9"
POP"NOPOP"
PART_NUMBER"A36096-046"
VOLTAGE"50V"
VALUE"1000PF"
MATERIAL"X7R"
PACK_TYPE"0402LF"
TOLERANCE"10%"
LOCATION"CT9"
CDS_LIB"mstr_discrete"
ROOM"VDDQ_KLM_PWR_VR"
SEC"1"
SEC_TYPE"0402LF";
"A"
$PN"1"45;
"B"
$PN"2"38;
%"CAP"
"1","(2925,-475)","0","mstr_discrete","I135";
;
CDS_SEC"1"
CDS_LOCATION"CT11"
LOCATION"CT11"
TOLERANCE"10%"
VOLTAGE"50V"
VALUE"1000PF"
MATERIAL"X7R"
PACK_TYPE"0402LF"
BOM_SS"NOPOP"
PART_NUMBER"A36096-046"
POP"NOPOP"
SEC_TYPE"0402LF"
SEC"1"
ROOM"VDDQ_KLM_PWR_VR"
CDS_LIB"mstr_discrete";
"A"
$PN"1"31;
"B"
$PN"2"34;
%"RES"
"1","(100,2025)","0","mstr_discrete","I138";
;
CDS_SEC"1"
CDS_LOCATION"RT5"
PACK_TYPE"0603"
PART_NUMBER"G22178-002"
MATERIAL"CHIP"
TOLERANCE"5.0%"
VALUE"0"
WATTAGE"1/10W"
LOCATION"RT5"
SEC_TYPE"0603"
SEC"1"
BOM_COST"NT_GBE_BASE"
ROOM"NIC_SPRV"
CDS_LIB"mstr_discrete";
"B"
$PN"2"43;
"A"
$PN"1"39;
%"RES"
"1","(225,-250)","0","mstr_discrete","I139";
;
CDS_SEC"1"
CDS_LOCATION"RT8"
LOCATION"RT8"
PART_NUMBER"G22178-002"
TOLERANCE"5.0%"
MATERIAL"CHIP"
VALUE"0"
WATTAGE"1/10W"
BOM_SS"NOPOP"
PACK_TYPE"0603"
BOM_COST"NT_GBE_BASE"
ROOM"NIC_SPRV"
CDS_LIB"mstr_discrete"
SEC_TYPE"0603"
SEC"1";
"B"
$PN"2"29;
"A"
$PN"1"36;
%"SC1U10V2KX-4-GP"
"1","(-425,225)","0","w_hdl","I147";
;
CDS_SEC"1"
CDS_LOCATION"C1A11"
RATED"10V"
PACK_SIZE"0402"
ATTRIBUTE"1UF"
TOLERANCE"10%"
BOM_SS"NOPOP"
VALUE"SC1U10V2KX-4-GP"
LOCATION"C1A11"
PACK_TYPE"SMD-BCG6"
SEC"1"
SEC_TYPE"SMD-BCG6"
PART_NUMBER"78.10523.8FL"
CDS_LIB"w_hdl"
CDS_LMAN_SYM_OUTLINE"-50,25,50,-25";
"2"
$PN"2"18;
"1"
$PN"1"20;
%"SC1U10V2KX-4-GP"
"1","(-475,2475)","0","w_hdl","I148";
;
CDS_SEC"1"
CDS_LOCATION"C1A2"
ATTRIBUTE"1UF"
VALUE"SC1U10V2KX-4-GP"
PACK_SIZE"0402"
RATED"10V"
TOLERANCE"10%"
LOCATION"C1A2"
CDS_LMAN_SYM_OUTLINE"-50,25,50,-25"
CDS_LIB"w_hdl"
PART_NUMBER"78.10523.8FL"
SEC_TYPE"SMD-BCG6"
SEC"1"
PACK_TYPE"SMD-BCG6";
"2"
$PN"2"12;
"1"
$PN"1"4;
%"1R3F-GP"
"1","(2825,1325)","0","w_hdl","I149";
;
CDS_SEC"1"
CDS_LOCATION"RT6"
RATED"1/10W"
TOLERANCE"1%"
PACK_SIZE"0603"
LOCATION"RT6"
ATTRIBUTE"1 OHM"
POP"NOPOP"
VALUE"1R3F-GP"
PACK_TYPE"RCL_GP"
SEC"1"
SEC_TYPE"RCL_GP"
PART_NUMBER"64.1R005.55L"
CDS_LIB"w_hdl"
CDS_LMAN_SYM_OUTLINE"-50,75,50,-75";
"2"
$PN"2"6;
"1"
$PN"1"38;
%"1R3F-GP"
"1","(2925,-800)","0","w_hdl","I150";
;
CDS_SEC"1"
CDS_LOCATION"RT7"
LOCATION"RT7"
PACK_SIZE"0603"
TOLERANCE"1%"
ATTRIBUTE"1 OHM"
POP"NOPOP"
VALUE"1R3F-GP"
RATED"1/10W"
BOM_SS"NOPOP"
CDS_LMAN_SYM_OUTLINE"-50,75,50,-75"
CDS_LIB"w_hdl"
PART_NUMBER"64.1R005.55L"
SEC_TYPE"RCL_GP"
SEC"1"
PACK_TYPE"RCL_GP";
"2"
$PN"2"8;
"1"
$PN"1"34;
%"IND-120NH-30-GP"
"1","(3775,1950)","1","w_hdl","I152";
;
CDS_SEC"1"
CDS_LOCATION"L1A2"
NEW_TYPE"IRMS=66A@DELTA_T<40C"
BOM_DS"068.9002N.1021"
DS_VALUE"90NH"
NEW_RATED"DS_ISAT=134A@25C"
LOCATION"L1A2"
BOM_SS"068.1202N.M001"
SS_ISAT"94A@25C"
SS_VALUE"120NH"
NEW_PACK_SIZE"DCR=0.17MOHM"
TYPE"IRMS=66A@DELTA_T<40C"
PACK_SIZE"DCR=0.17MOHM"
RATED"ISAT=94A@25C"
ATTRIBUTE"120NH"
VALUE"IND-120NH-30-GP"
PACK_TYPE"DISCRET-GB2"
SEC"1"
SEC_TYPE"DISCRET-GB2"
CDS_LMAN_SYM_OUTLINE"-75,100,75,-100"
CDS_LIB"w_hdl"
PART_NUMBER"068.1202N.M001";
"F"
$PN"2"1;
"S"
$PN"1"45;
%"IND-120NH-30-GP"
"1","(3775,-300)","1","w_hdl","I153";
;
CDS_SEC"1"
CDS_LOCATION"L1A1"
NEW_PACK_SIZE"DCR=0.17MOHM"
DS_VALUE"90NH"
LOCATION"L1A1"
BOM_DS"068.9002N.1021"
BOM_SS"NOPOP"
NEW_TYPE"IRMS=66A@DELTA_T<40C"
NEW_RATED"DS_ISAT=134A@25C"
PART_NUMBER"068.1202N.M001"
CDS_LIB"w_hdl"
CDS_LMAN_SYM_OUTLINE"-75,100,75,-100"
SEC_TYPE"DISCRET-GB2"
SEC"1"
PACK_TYPE"DISCRET-GB2"
VALUE"IND-120NH-30-GP"
ATTRIBUTE"120NH"
RATED"ISAT=94A@25C"
PACK_SIZE"DCR=0.17MOHM"
TYPE"IRMS=66A@DELTA_T<40C";
"F"
$PN"2"13;
"S"
$PN"1"31;
%"RES"
"1","(-750,3100)","0","mstr_discrete","I154";
;
WATTAGE"1/16W"
LOCATION"R9L9"
PART_NUMBER"G21497-005"
MATERIAL"CHIP"
VALUE"0.0"
PACK_TYPE"0402"
TOLERANCE"5%"
CDS_LOCATION"R9L9"
BOM_COST"PROC_SIDEBAND"
CDS_LIB"mstr_discrete"
SEC_TYPE"0402"
SEC"1"
ROOM"CPU0"
CDS_SEC"1";
"B"
$PN"2"4;
"A"
$PN"1"25;
%"RES"
"1","(-675,800)","0","mstr_discrete","I155";
;
BOM_SS"NOPOP"
WATTAGE"1/16W"
PART_NUMBER"G21497-005"
VALUE"0.0"
LOCATION"R9L4"
MATERIAL"CHIP"
TOLERANCE"5%"
PACK_TYPE"0402"
CDS_LOCATION"R9L4"
BOM_COST"PROC_SIDEBAND"
CDS_LIB"mstr_discrete"
SEC_TYPE"0402"
SEC"1"
ROOM"CPU0"
CDS_SEC"1";
"B"
$PN"2"20;
"A"
$PN"1"21;
%"GND"
"1","(2675,1475)","0","mstr_symbols","I19";
;
HDL_POWER"GND"
BODY_TYPE"PLUMBING"
BOM_COST"VDDQ_KLM_PWR_VR"
ROOM"VDDQ_KLM_PWR_VR"
VOLTAGE"0"
CDS_LIB"mstr_symbols"
SIZE"1B";
"A\NAC"11;
%"GND"
"1","(-2250,2125)","0","mstr_symbols","I35";
;
HDL_POWER"GND"
BODY_TYPE"PLUMBING"
SIZE"1B"
VOLTAGE"0"
CDS_LIB"mstr_symbols"
ROOM"VDDQ_KLM_PWR_VR"
BOM_COST"VDDQ_KLM_PWR_VR";
"A\NAC"12;
%"CAP"
"1","(-825,1925)","2","mstr_discrete","I44";
;
CDS_SEC"1"
PART_NUMBER"A36096-104"
TOLERANCE"10%"
VOLTAGE"16V"
VALUE"0.220UF"
LOCATION"C1A18"
MATERIAL"X7R"
PACK_TYPE"0402"
SEC_TYPE"0402"
SPOF"TRUE"
SEC"1"
ROOM"VDDQ_KLM_PWR_VR"
CDS_LOCATION"C1A18"
CDS_LIB"mstr_discrete";
"A"
$PN"1"39;
"B"
$PN"2"23;
%"CAP"
"1","(-2250,2500)","0","mstr_discrete","I45";
;
CDS_SEC"1"
LOCATION"C9L11"
VOLTAGE"16V"
VALUE"10UF"
PACK_TYPE"0805"
TOLERANCE"10%"
MATERIAL"X6S"
PART_NUMBER"C95333-007"
CDS_LIB"mstr_discrete"
CDS_LOCATION"C9L11"
ROOM"VDDQ_KLM_PWR_VR"
SEC"1"
SEC_TYPE"0805";
"A"
$PN"1"19;
"B"
$PN"2"12;
%"CAP"
"1","(-1975,2500)","0","mstr_discrete","I46";
;
CDS_SEC"1"
LOCATION"C9L10"
VOLTAGE"16V"
TOLERANCE"10%"
VALUE"10UF"
MATERIAL"X6S"
PART_NUMBER"C95333-007"
PACK_TYPE"0805"
CDS_LIB"mstr_discrete"
CDS_LOCATION"C9L10"
ROOM"VDDQ_KLM_PWR_VR"
SEC_TYPE"0805"
SEC"1";
"A"
$PN"1"19;
"B"
$PN"2"12;
%"CAP"
"1","(-1700,2500)","0","mstr_discrete","I47";
;
CDS_SEC"1"
VOLTAGE"16V"
TOLERANCE"10%"
MATERIAL"X6S"
PACK_TYPE"0805"
VALUE"10UF"
PART_NUMBER"C95333-007"
LOCATION"C9L6"
CDS_LIB"mstr_discrete"
CDS_LOCATION"C9L6"
SEC_TYPE"0805"
SEC"1"
ROOM"VDDQ_KLM_PWR_VR";
"A"
$PN"1"19;
"B"
$PN"2"12;
%"CAP"
"1","(-1425,2475)","0","mstr_discrete","I48";
;
CDS_SEC"1"
VOLTAGE"16V"
LOCATION"C1A19"
PART_NUMBER"D97712-011"
TOLERANCE"10%"
PACK_TYPE"0402"
MATERIAL"X6S"
VALUE"1.0UF"
ROOM"VDDQ_KLM_PWR_VR"
SEC"1"
SEC_TYPE"0402"
CDS_LIB"mstr_discrete"
CDS_LOCATION"C1A19";
"A"
$PN"1"19;
"B"
$PN"2"12;
%"CAP"
"1","(-900,2500)","0","mstr_discrete","I50";
;
CDS_SEC"1"
CDS_LOCATION"C1B20"
PACK_TYPE"0402"
PART_NUMBER"D97712-011"
VOLTAGE"16V"
VALUE"1.0UF"
MATERIAL"X6S"
LOCATION"C1B20"
TOLERANCE"10%"
CDS_LIB"mstr_discrete"
ROOM"VDDQ_KLM_PWR_VR"
SEC"1"
SEC_TYPE"0402";
"A"
$PN"1"25;
"B"
$PN"2"12;
%"CAP_A"
"1","(-1175,2475)","0","dev_discrete","I51";
;
PACK_TYPE"0402V"
PART_NUMBER"A36096-030"
MATERIAL"X7R"
TOLERANCE"10%"
VALUE"0.1UF"
LOCATION"C1A10"
VOLTAGE"16V"
SEC"1"
SEC_TYPE"0402V"
ROOM"VDDQ_KLM_PWR_VR"
CDS_SEC"1"
CDS_LIB"dev_discrete"
CDS_LOCATION"C1A10";
"B"
$PN"2"12;
"A"
$PN"1"19;
%"CAP"
"1","(-100,2475)","0","mstr_discrete","I54";
;
CDS_SEC"1"
CDS_LOCATION"C1B21"
PART_NUMBER"A36096-155"
VOLTAGE"16V"
PACK_TYPE"0402"
VALUE"0.22UF"
TOLERANCE"10%"
MATERIAL"X7R"
LOCATION"C1B21"
CDS_LIB"mstr_discrete"
ROOM"VDDQ_KLM_PWR_VR"
SEC"1"
SEC_TYPE"0402";
"A"
$PN"1"4;
"B"
$PN"2"12;
%"CAP"
"1","(4350,1775)","0","mstr_discrete","I6";
;
CDS_SEC"1"
VALUE"22UF"
VOLTAGE"4V"
TOLERANCE"20%"
MATERIAL"X6S"
LOCATION"C1A12"
PACK_TYPE"0805LF"
PART_NUMBER"C95333-002"
GROUP"PWR_MLCC_CAP"
BOM_COST"VDDQ_KLM_PWR_VR"
SEC_TYPE"0805LF"
SEC"1"
ROOM"VDDQ_KLM_PWR_VR"
CDS_LIB"mstr_discrete"
CDS_LOCATION"C1A12";
"A"
$PN"1"1;
"B"
$PN"2"15;
%"PVDDQ_KLM"
"1","(4375,-225)","0","mstr_symbols","I64";
;
VOLTAGE"1.2V"
BOM_COST"VDDQ_KLM_PWR_VR"
CDS_LIB"mstr_symbols"
ROOM"VDDQ_KLM_PWR_VR"
BODY_TYPE"PLUMBING"
HDL_POWER"PVDDQ_KLM";
"G\NAC"13;
%"CAP"
"1","(4375,-475)","0","mstr_discrete","I68";
;
CDS_SEC"1"
MATERIAL"X6S"
VALUE"22UF"
LOCATION"C1A1"
TOLERANCE"20%"
PACK_TYPE"0805LF"
VOLTAGE"4V"
PART_NUMBER"C95333-002"
BOM_SS"NOPOP"
GROUP"PWR_MLCC_CAP"
CDS_LIB"mstr_discrete"
ROOM"VDDQ_KLM_PWR_VR"
CDS_LOCATION"C1A1"
BOM_COST"VDDQ_KLM_PWR_VR"
SEC_TYPE"0805LF"
SEC"1";
"A"
$PN"1"13;
"B"
$PN"2"14;
%"GND"
"1","(4375,-650)","0","mstr_symbols","I69";
;
HDL_POWER"GND"
BODY_TYPE"PLUMBING"
ROOM"VDDQ_KLM_PWR_VR"
BOM_COST"VDDQ_KLM_PWR_VR"
CDS_LIB"mstr_symbols"
VOLTAGE"0"
SIZE"1B";
"A\NAC"14;
%"GND"
"1","(4350,1600)","0","mstr_symbols","I7";
;
SIZE"1B"
BOM_COST"VDDQ_KLM_PWR_VR"
VOLTAGE"0"
CDS_LIB"mstr_symbols"
ROOM"VDDQ_KLM_PWR_VR"
BODY_TYPE"PLUMBING"
HDL_POWER"GND";
"A\NAC"15;
%"GND"
"1","(2700,-775)","0","mstr_symbols","I70";
;
ROOM"VDDQ_KLM_PWR_VR"
BOM_COST"VDDQ_KLM_PWR_VR"
SIZE"1B"
VOLTAGE"0"
CDS_LIB"mstr_symbols"
BODY_TYPE"PLUMBING"
HDL_POWER"GND";
"A\NAC"16;
%"CAP"
"1","(-75,250)","0","mstr_discrete","I72";
;
CDS_SEC"1"
MATERIAL"X7R"
PART_NUMBER"A36096-155"
VALUE"0.22UF"
BOM_SS"NOPOP"
VOLTAGE"16V"
TOLERANCE"10%"
PACK_TYPE"0402"
LOCATION"C1A13"
SEC"1"
SEC_TYPE"0402"
ROOM"VDDQ_KLM_PWR_VR"
CDS_LOCATION"C1A13"
CDS_LIB"mstr_discrete";
"A"
$PN"1"20;
"B"
$PN"2"18;
%"CAP"
"1","(-775,-350)","2","mstr_discrete","I75";
;
CDS_SEC"1"
LOCATION"C1A8"
BOM_SS"NOPOP"
PART_NUMBER"A36096-104"
VALUE"0.220UF"
VOLTAGE"16V"
PACK_TYPE"0402"
TOLERANCE"10%"
MATERIAL"X7R"
CDS_LIB"mstr_discrete"
SPOF"TRUE"
SEC"1"
CDS_LOCATION"C1A8"
SEC_TYPE"0402"
ROOM"VDDQ_KLM_PWR_VR";
"A"
$PN"1"36;
"B"
$PN"2"30;
%"CAP"
"1","(-825,250)","0","mstr_discrete","I77";
;
CDS_SEC"1"
VOLTAGE"16V"
PART_NUMBER"D97712-011"
LOCATION"C1A6"
VALUE"1.0UF"
BOM_SS"NOPOP"
PACK_TYPE"0402"
MATERIAL"X6S"
TOLERANCE"10%"
CDS_LOCATION"C1A6"
CDS_LIB"mstr_discrete"
ROOM"VDDQ_KLM_PWR_VR"
SEC_TYPE"0402"
SEC"1";
"A"
$PN"1"21;
"B"
$PN"2"18;
%"CAP_A"
"1","(-1075,250)","0","dev_discrete","I78";
;
TOLERANCE"10%"
VOLTAGE"16V"
LOCATION"C1A20"
VALUE"0.1UF"
MATERIAL"X7R"
PACK_TYPE"0402V"
PART_NUMBER"A36096-030"
CDS_LIB"dev_discrete"
CDS_LOCATION"C1A20"
CDS_SEC"1"
ROOM"VDDQ_KLM_PWR_VR"
SEC_TYPE"0402V"
SEC"1";
"B"
$PN"2"18;
"A"
$PN"1"17;
%"CAP"
"1","(-1350,250)","0","mstr_discrete","I79";
;
CDS_SEC"1"
VOLTAGE"16V"
TOLERANCE"10%"
MATERIAL"X6S"
PACK_TYPE"0402"
PART_NUMBER"D97712-011"
VALUE"1.0UF"
LOCATION"C1A9"
SEC"1"
SEC_TYPE"0402"
ROOM"VDDQ_KLM_PWR_VR"
CDS_LOCATION"C1A9"
CDS_LIB"mstr_discrete";
"A"
$PN"1"17;
"B"
$PN"2"18;
%"CAP"
"1","(-1625,250)","0","mstr_discrete","I80";
;
CDS_SEC"1"
LOCATION"C9L5"
PACK_TYPE"0805"
PART_NUMBER"C95333-007"
MATERIAL"X6S"
TOLERANCE"10%"
VOLTAGE"16V"
VALUE"10UF"
CDS_LIB"mstr_discrete"
CDS_LOCATION"C9L5"
ROOM"VDDQ_KLM_PWR_VR"
SEC_TYPE"0805"
SEC"1";
"A"
$PN"1"17;
"B"
$PN"2"18;
%"CAP"
"1","(-1900,250)","0","mstr_discrete","I81";
;
CDS_SEC"1"
PART_NUMBER"C95333-007"
MATERIAL"X6S"
TOLERANCE"10%"
VOLTAGE"16V"
PACK_TYPE"0805"
VALUE"10UF"
LOCATION"C9L13"
CDS_LIB"mstr_discrete"
ROOM"VDDQ_KLM_PWR_VR"
CDS_LOCATION"C9L13"
SEC"1"
SEC_TYPE"0805";
"A"
$PN"1"17;
"B"
$PN"2"18;
%"VCC_CORE"
"1","(-2175,550)","0","mstr_symbols","I83";
;
HDL_POWER"VR_FET_SW_P12V_STBY_PVDDQ_KLM"
CDS_LIB"mstr_symbols";
"A"17;
%"CAP"
"1","(-2175,250)","0","mstr_discrete","I84";
;
CDS_SEC"1"
TOLERANCE"10%"
VOLTAGE"16V"
VALUE"10UF"
PART_NUMBER"C95333-007"
MATERIAL"X6S"
PACK_TYPE"0805"
LOCATION"C9L14"
CDS_LIB"mstr_discrete"
CDS_LOCATION"C9L14"
ROOM"VDDQ_KLM_PWR_VR"
SEC_TYPE"0805"
SEC"1";
"A"
$PN"1"17;
"B"
$PN"2"18;
%"GND"
"1","(-2175,-150)","0","mstr_symbols","I85";
;
HDL_POWER"GND"
BODY_TYPE"PLUMBING"
SIZE"1B"
CDS_LIB"mstr_symbols"
VOLTAGE"0"
BOM_COST"VDDQ_KLM_PWR_VR"
ROOM"VDDQ_KLM_PWR_VR";
"A\NAC"18;
%"VCC_CORE"
"1","(-1850,2850)","0","mstr_symbols","I86";
;
HDL_POWER"VR_FET_SW_P12V_STBY_PVDDQ_KLM"
CDS_LIB"mstr_symbols";
"A"19;
%"P5V_STBY"
"1","(550,925)","0","mstr_symbols","I88";
;
VOLTAGE"5.0V"
CDS_LIB"mstr_symbols"
SIZE"1B"
BODY_TYPE"PLUMBING"
HDL_POWER"P5V_STBY";
"G\NAC"20;
END.
